G04 ================== begin FILE IDENTIFICATION RECORD ==================*
G04 Layout Name:  15669-1.brd*
G04 Film Name:    BSMD*
G04 File Format:  Gerber RS274X*
G04 File Origin:  Cadence Allegro 16.5-S056*
G04 Origin Date:  Wed Nov 16 04:08:02 2016*
G04 *
G04 Layer:  VIA CLASS/PASTEMASK_BOTTOM*
G04 Layer:  PIN/PASTEMASK_BOTTOM*
G04 Layer:  PACKAGE GEOMETRY/PASTEMASK_BOTTOM*
G04 Layer:  DRAWING FORMAT/LAYER_PCB_STORY*
G04 Layer:  DRAWING FORMAT/LAYER_PAST_B*
G04 Layer:  BOARD GEOMETRY/PANEL_OUTLINE*
G04 *
G04 Offset:    (0.00 0.00)*
G04 Mirror:    No*
G04 Mode:      Positive*
G04 Rotation:  0*
G04 FullContactRelief:  No*
G04 UndefLineWidth:     6.00*
G04 ================== end FILE IDENTIFICATION RECORD ====================*
%FSLAX35Y35*MOIN*%
%IR0*IPPOS*OFA0.00000B0.00000*MIA0B0*SFA1.00000B1.00000*%
%ADD13R,.23X.032*%
%ADD10C,.04*%
%ADD12C,.028*%
%ADD11R,.098X.02*%
%ADD14C,.02*%
%ADD15C,.006*%
G75*
%LPD*%
G75*
G36*
G01X1021245Y1493247D02*
Y1510922D01*
X995645D01*
Y1493247D01*
X1021245D01*
G37*
G36*
G01Y1473722D02*
Y1491397D01*
X995645D01*
Y1473722D01*
X1021245D01*
G37*
G36*
G01Y1453247D02*
Y1470922D01*
X995645D01*
Y1453247D01*
X1021245D01*
G37*
G36*
G01Y1433722D02*
Y1451397D01*
X995645D01*
Y1433722D01*
X1021245D01*
G37*
G36*
G01Y1573247D02*
Y1590922D01*
X995645D01*
Y1573247D01*
X1021245D01*
G37*
G36*
G01Y1553722D02*
Y1571397D01*
X995645D01*
Y1553722D01*
X1021245D01*
G37*
G36*
G01Y1533247D02*
Y1550922D01*
X995645D01*
Y1533247D01*
X1021245D01*
G37*
G36*
G01Y1513722D02*
Y1531397D01*
X995645D01*
Y1513722D01*
X1021245D01*
G37*
G36*
G01X1021244Y1593722D02*
Y1610922D01*
X995645D01*
Y1593722D01*
X1021244D01*
G37*
G54D10*
X-49168Y52138D03*
X26000Y1965500D03*
X1009500Y27500D03*
X1010500Y1966000D03*
X1085741Y22661D03*
Y1967598D03*
G54D11*
X8858Y629693D03*
Y626544D03*
Y623394D03*
Y620245D03*
Y617095D03*
Y613945D03*
Y610796D03*
Y607646D03*
Y604496D03*
Y601347D03*
Y598197D03*
Y702134D03*
Y698985D03*
Y695835D03*
Y692685D03*
Y689536D03*
Y686386D03*
Y683237D03*
Y680087D03*
Y676937D03*
Y673788D03*
Y670638D03*
Y667489D03*
Y664339D03*
Y661189D03*
Y658040D03*
Y654890D03*
Y651741D03*
Y648591D03*
Y645441D03*
Y642292D03*
Y639142D03*
Y635993D03*
Y632843D03*
Y774575D03*
Y771426D03*
Y768276D03*
Y765126D03*
Y761977D03*
Y758827D03*
Y755678D03*
Y752528D03*
Y749378D03*
Y733630D03*
Y730481D03*
Y727331D03*
Y724182D03*
Y721032D03*
Y717882D03*
Y714733D03*
Y711583D03*
Y708433D03*
Y705284D03*
Y847016D03*
Y843867D03*
Y840717D03*
Y837567D03*
Y834418D03*
Y831268D03*
Y828119D03*
Y824969D03*
Y821819D03*
Y818670D03*
Y815520D03*
Y812371D03*
Y809221D03*
Y806071D03*
Y802922D03*
Y799772D03*
Y796622D03*
Y793473D03*
Y790323D03*
Y787174D03*
Y784024D03*
Y780874D03*
Y777725D03*
Y919457D03*
Y916308D03*
Y913158D03*
Y910008D03*
Y906859D03*
Y903709D03*
Y900559D03*
Y897410D03*
Y894260D03*
Y891111D03*
Y887961D03*
Y884811D03*
Y881662D03*
Y878512D03*
Y875363D03*
Y872213D03*
Y869063D03*
Y865914D03*
Y862764D03*
Y859615D03*
Y856465D03*
Y853315D03*
Y850166D03*
Y922607D03*
Y1138355D03*
Y1135205D03*
Y1132056D03*
Y1128906D03*
Y1125756D03*
Y1122607D03*
Y1119457D03*
Y1116308D03*
Y1113158D03*
Y1110008D03*
Y1106859D03*
Y1103709D03*
Y1100559D03*
Y1097410D03*
Y1094260D03*
Y1210796D03*
Y1207646D03*
Y1204496D03*
Y1201347D03*
Y1198197D03*
Y1195048D03*
Y1191898D03*
Y1188748D03*
Y1185599D03*
Y1182449D03*
Y1179300D03*
Y1176150D03*
Y1173000D03*
Y1169851D03*
Y1166701D03*
Y1163552D03*
Y1160402D03*
Y1157252D03*
Y1154103D03*
Y1150953D03*
Y1147804D03*
Y1144654D03*
Y1141504D03*
Y1283237D03*
Y1280087D03*
Y1276937D03*
Y1273788D03*
Y1270638D03*
Y1267489D03*
Y1264339D03*
Y1261189D03*
Y1258040D03*
Y1254890D03*
Y1251741D03*
Y1248591D03*
Y1245441D03*
Y1229693D03*
Y1226544D03*
Y1223394D03*
Y1220245D03*
Y1217095D03*
Y1213945D03*
Y1355678D03*
Y1352528D03*
Y1349378D03*
Y1346229D03*
Y1343079D03*
Y1339930D03*
Y1336780D03*
Y1333630D03*
Y1330481D03*
Y1327331D03*
Y1324182D03*
Y1321032D03*
Y1317882D03*
Y1314733D03*
Y1311583D03*
Y1308434D03*
Y1305284D03*
Y1302134D03*
Y1298985D03*
Y1295835D03*
Y1292685D03*
Y1289536D03*
Y1286386D03*
Y1418670D03*
Y1415520D03*
Y1412371D03*
Y1409221D03*
Y1406071D03*
Y1402922D03*
Y1399772D03*
Y1396622D03*
Y1393473D03*
Y1390323D03*
Y1387174D03*
Y1384024D03*
Y1380874D03*
Y1377725D03*
Y1374575D03*
Y1371426D03*
Y1368276D03*
Y1365126D03*
Y1361977D03*
Y1358827D03*
Y1574574D03*
Y1571425D03*
Y1568275D03*
Y1565126D03*
Y1561976D03*
Y1558826D03*
Y1555677D03*
Y1552527D03*
Y1549378D03*
Y1546228D03*
Y1543078D03*
Y1539929D03*
Y1536779D03*
Y1533630D03*
Y1530480D03*
Y1527330D03*
Y1524181D03*
Y1521031D03*
Y1517881D03*
Y1514732D03*
Y1511582D03*
Y1647015D03*
Y1643866D03*
Y1640716D03*
Y1637567D03*
Y1634417D03*
Y1631267D03*
Y1628118D03*
Y1624968D03*
Y1621818D03*
Y1618669D03*
Y1615519D03*
Y1612370D03*
Y1609220D03*
Y1606070D03*
Y1602921D03*
Y1599771D03*
Y1596622D03*
Y1593472D03*
Y1590322D03*
Y1587173D03*
Y1584023D03*
Y1580874D03*
Y1577724D03*
Y1719456D03*
Y1716307D03*
Y1713157D03*
Y1710007D03*
Y1706858D03*
Y1703708D03*
Y1700559D03*
Y1697409D03*
Y1694259D03*
Y1691110D03*
Y1687960D03*
Y1684811D03*
Y1681661D03*
Y1678511D03*
Y1675362D03*
Y1672212D03*
Y1669063D03*
Y1665913D03*
Y1662763D03*
Y1791897D03*
Y1788748D03*
Y1785598D03*
Y1782448D03*
Y1779299D03*
Y1776149D03*
Y1773000D03*
Y1769850D03*
Y1766700D03*
Y1763551D03*
Y1760401D03*
Y1757252D03*
Y1754102D03*
Y1750952D03*
Y1747803D03*
Y1744653D03*
Y1741504D03*
Y1738354D03*
Y1735204D03*
Y1732055D03*
Y1728905D03*
Y1725756D03*
Y1722606D03*
Y1835992D03*
Y1832842D03*
Y1829693D03*
Y1826543D03*
Y1823393D03*
Y1820244D03*
Y1817094D03*
Y1813944D03*
Y1810795D03*
Y1807645D03*
Y1804496D03*
Y1801346D03*
Y1798196D03*
Y1795047D03*
G54D12*
X37000Y762000D03*
X105750Y217750D03*
X73900Y269500D03*
X80100Y805500D03*
X80215Y787900D03*
X43387Y803500D03*
X40087Y788400D03*
X41000Y908000D03*
X56000Y967000D03*
X81175Y1066404D03*
X51944Y1232506D03*
X79390Y1327082D03*
X65000Y1336000D03*
X50100Y1317400D03*
X94642Y1456100D03*
X55738Y1578587D03*
X58777Y1585826D03*
X49555Y1583740D03*
X45402Y1712309D03*
X45150Y1720650D03*
X55500Y1763000D03*
X83600Y1736600D03*
X53200Y1865800D03*
X63579Y1894881D03*
X70650Y1897792D03*
X50100Y1872800D03*
X148000Y966500D03*
X142066Y958234D03*
X141250Y978050D03*
X132000Y1042000D03*
X112700Y1079600D03*
X162500Y1380500D03*
X122000Y1727500D03*
X147200Y1756600D03*
X157900Y1770500D03*
X243590Y1779507D03*
X320700Y396100D03*
X318700Y469800D03*
X328250Y441400D03*
X318800Y823700D03*
X328250Y1233000D03*
X311500Y1374500D03*
X390000Y820500D03*
X383140Y1179640D03*
X335025Y1701725D03*
X395500Y1703000D03*
X689000Y1592500D03*
X719901Y939198D03*
X740464Y1499388D03*
X698500Y1812000D03*
X831000Y1625000D03*
X851000Y1627000D03*
X903500Y1627500D03*
X873500Y1625500D03*
X975000Y1425000D03*
X950000Y1440000D03*
X960000Y1460000D03*
X950000Y1470000D03*
Y1500000D03*
X960000Y1540000D03*
X950000Y1550000D03*
X940000Y1570000D03*
Y1605000D03*
X933500Y1625000D03*
X961500Y1624500D03*
X931000Y1671500D03*
X930000Y1685000D03*
X939500Y1698000D03*
X913000Y1717750D03*
G54D13*
X1009744Y1646102D03*
Y1641102D03*
Y1636102D03*
Y1631102D03*
Y1626102D03*
Y1621102D03*
Y1676102D03*
Y1671102D03*
Y1666102D03*
Y1661102D03*
Y1656102D03*
Y1651102D03*
G54D14*
G01X-106883Y-224955D02*
Y-304955D01*
G01Y-260455D02*
X1019417D01*
G01X-106883Y-304955D02*
X1019417D01*
G01X-110883Y-208955D02*
G02I-12000J0D01*
G01X-116033D02*
G02I-6850J0D01*
G01X-122883Y-224955D02*
Y-192955D01*
G01X-106883Y-208955D02*
X-138883D01*
G01X-106883Y-224955D02*
X1019417D01*
G01X231917D02*
Y-304955D01*
G01X369417Y-224955D02*
Y-304955D01*
G01X484417Y-224955D02*
Y-304955D01*
G01X651917Y-224955D02*
Y-304955D01*
G01X821917Y-224955D02*
Y-304955D01*
G01X1019417Y-224955D02*
Y-304955D01*
G01X1047417Y-208955D02*
G02I-12000J0D01*
G01X1042267D02*
G02I-6850J0D01*
G01X1035417Y-224955D02*
Y-192955D01*
G01X1051417Y-208955D02*
X1019417D01*
G54D15*
G01X-90900Y-277455D02*
Y-294955D01*
X-82166D01*
G01X-69033Y-283289D02*
Y-294955D01*
G01Y-278622D02*
X-69470Y-278330D01*
Y-277747D01*
X-69033Y-277455D01*
X-68596Y-277747D01*
Y-278330D01*
X-69033Y-278622D01*
G01X-54590Y-299330D02*
X-53061Y-300497D01*
X-51315Y-300788D01*
X-49787Y-300497D01*
X-48476Y-299039D01*
X-47603Y-296997D01*
Y-283289D01*
G01Y-285622D02*
X-48476Y-284455D01*
X-49787Y-283580D01*
X-51315Y-283289D01*
X-53061Y-283872D01*
X-54153Y-285038D01*
X-55027Y-287080D01*
X-55463Y-289122D01*
X-55245Y-290872D01*
X-54371Y-292914D01*
X-53061Y-294372D01*
X-51315Y-294955D01*
X-50005Y-294663D01*
X-48476Y-293497D01*
X-47603Y-292331D01*
G01X-37745Y-294955D02*
Y-277455D01*
G01Y-285913D02*
X-36653Y-284455D01*
X-35561Y-283580D01*
X-33815Y-283289D01*
X-32505Y-283580D01*
X-30976Y-284747D01*
X-30321Y-286497D01*
Y-294955D01*
G01X-16533Y-277455D02*
Y-294955D01*
G01X-19590Y-283289D02*
X-13476D01*
G01X-2745Y-294955D02*
Y-283289D01*
G01Y-286205D02*
X-1871Y-284747D01*
X-561Y-283580D01*
X1185Y-283289D01*
X2713Y-283580D01*
X4024Y-284747D01*
X4679Y-286788D01*
Y-294955D01*
G01X18467Y-283289D02*
Y-294955D01*
G01Y-278622D02*
X18030Y-278330D01*
Y-277747D01*
X18467Y-277455D01*
X18904Y-277747D01*
Y-278330D01*
X18467Y-278622D01*
G01X32255Y-294955D02*
Y-283289D01*
G01Y-286205D02*
X33129Y-284747D01*
X34439Y-283580D01*
X36185Y-283289D01*
X37713Y-283580D01*
X39024Y-284747D01*
X39679Y-286788D01*
Y-294955D01*
G01X50410Y-299330D02*
X51939Y-300497D01*
X53685Y-300788D01*
X55213Y-300497D01*
X56524Y-299039D01*
X57397Y-296997D01*
Y-283289D01*
G01Y-285622D02*
X56524Y-284455D01*
X55213Y-283580D01*
X53685Y-283289D01*
X51939Y-283872D01*
X50847Y-285038D01*
X49973Y-287080D01*
X49537Y-289122D01*
X49755Y-290872D01*
X50629Y-292914D01*
X51939Y-294372D01*
X53685Y-294955D01*
X54995Y-294663D01*
X56524Y-293497D01*
X57397Y-292331D01*
G01X84100Y-294955D02*
Y-277455D01*
X89340D01*
X91087Y-278330D01*
X92397Y-280372D01*
X92834Y-282705D01*
X92397Y-285038D01*
X91305Y-286788D01*
X89340Y-287664D01*
X84100D01*
G01X101164Y-294955D02*
Y-277455D01*
X105530D01*
X107277Y-278330D01*
X108587Y-279497D01*
X109679Y-281246D01*
X110552Y-283289D01*
X110770Y-286205D01*
X110552Y-289122D01*
X109679Y-291164D01*
X108587Y-292914D01*
X107277Y-294080D01*
X105530Y-294955D01*
X101164D01*
G01X119100D02*
Y-277455D01*
X124340D01*
X126087Y-278330D01*
X127397Y-280372D01*
X127834Y-282705D01*
X127397Y-285038D01*
X126305Y-286788D01*
X124340Y-287664D01*
X119100D01*
G01X142713Y-285622D02*
X143587Y-284747D01*
X144242Y-283289D01*
X144679Y-281246D01*
X144242Y-279497D01*
X143369Y-278330D01*
X141840Y-277455D01*
X135945D01*
Y-294955D01*
X143150D01*
X144679Y-293789D01*
X145552Y-292038D01*
X145989Y-289997D01*
X145552Y-287955D01*
X144242Y-286205D01*
X142713Y-285622D01*
X135945D01*
G01X171600Y-294955D02*
Y-277455D01*
X176840D01*
X178587Y-278330D01*
X179897Y-280372D01*
X180334Y-282705D01*
X179897Y-285038D01*
X178805Y-286788D01*
X176840Y-287664D01*
X171600D01*
G01X188008Y-277455D02*
X193467Y-294955D01*
X198926Y-277455D01*
G01X210967D02*
Y-294955D01*
G01X205945Y-277455D02*
X215989D01*
G01X21540Y-249955D02*
Y-232455D01*
X27217Y-247038D01*
X32894Y-232455D01*
Y-249955D01*
G01X44717D02*
X43407Y-249663D01*
X42097Y-248497D01*
X41223Y-246455D01*
X40787Y-244122D01*
X41223Y-241788D01*
X42097Y-239747D01*
X43407Y-238580D01*
X44717Y-238289D01*
X46027Y-238580D01*
X47337Y-239747D01*
X48210Y-241788D01*
X48429Y-244122D01*
X48210Y-246455D01*
X47337Y-248497D01*
X46027Y-249663D01*
X44717Y-249955D01*
G01X66147Y-232455D02*
Y-249955D01*
G01Y-247331D02*
X65274Y-248789D01*
X63963Y-249663D01*
X62435Y-249955D01*
X60689Y-249372D01*
X59379Y-247914D01*
X58505Y-246164D01*
X58287Y-244122D01*
X58505Y-242080D01*
X59379Y-240330D01*
X60689Y-238872D01*
X62435Y-238289D01*
X63963Y-238580D01*
X65055Y-239164D01*
X66147Y-240330D01*
G01X76442Y-242080D02*
X83429D01*
X82774Y-240038D01*
X81682Y-238872D01*
X80154Y-238289D01*
X78625Y-238580D01*
X77315Y-239455D01*
X76442Y-241497D01*
X76005Y-243247D01*
Y-244997D01*
X76442Y-246747D01*
X77534Y-248497D01*
X78844Y-249663D01*
X80372Y-249955D01*
X81900Y-249372D01*
X83429Y-247622D01*
G01X97217Y-249955D02*
Y-232455D01*
G01X252500Y-249955D02*
Y-232455D01*
X257740D01*
X259487Y-233330D01*
X260797Y-235372D01*
X261234Y-237705D01*
X260797Y-240038D01*
X259705Y-241788D01*
X257740Y-242664D01*
X252500D01*
G01X279170Y-233914D02*
X277860Y-233038D01*
X276332Y-232455D01*
X274585D01*
X272620Y-233330D01*
X271092Y-234788D01*
X270000Y-236539D01*
X269127Y-239455D01*
X268908Y-242080D01*
X269345Y-244705D01*
X270000Y-246455D01*
X271310Y-248205D01*
X272839Y-249372D01*
X274367Y-249955D01*
X275895D01*
X277424Y-249372D01*
X278734Y-248497D01*
X279826Y-247331D01*
G01X293613Y-240622D02*
X294487Y-239747D01*
X295142Y-238289D01*
X295579Y-236246D01*
X295142Y-234497D01*
X294269Y-233330D01*
X292740Y-232455D01*
X286845D01*
Y-249955D01*
X294050D01*
X295579Y-248789D01*
X296452Y-247038D01*
X296889Y-244997D01*
X296452Y-242955D01*
X295142Y-241205D01*
X293613Y-240622D01*
X286845D01*
G01X302817Y-255788D02*
X315917D01*
G01X321845Y-249955D02*
Y-232455D01*
X331889Y-249955D01*
Y-232455D01*
G01X344367Y-249955D02*
X342620Y-249663D01*
X341092Y-248497D01*
X339782Y-246747D01*
X338908Y-244705D01*
X338472Y-242372D01*
Y-240038D01*
X338908Y-237705D01*
X339782Y-235663D01*
X341092Y-233914D01*
X342620Y-232747D01*
X344367Y-232455D01*
X346113Y-232747D01*
X347642Y-233914D01*
X348952Y-235663D01*
X349826Y-237705D01*
X350262Y-240038D01*
Y-242372D01*
X349826Y-244705D01*
X348952Y-246747D01*
X347642Y-248497D01*
X346113Y-249663D01*
X344367Y-249955D01*
G01X265617Y-294955D02*
Y-277455D01*
X262997Y-280955D01*
G01Y-294955D02*
X268237D01*
G01X278314Y-292331D02*
X279623Y-293789D01*
X281152Y-294663D01*
X283117Y-294955D01*
X285082Y-294372D01*
X286610Y-293205D01*
X287702Y-291164D01*
X287920Y-288830D01*
X287484Y-286497D01*
X286392Y-285038D01*
X284863Y-283872D01*
X283335Y-283580D01*
X281807Y-283872D01*
X279842Y-285038D01*
X280497Y-277455D01*
X286392D01*
G01X296469Y-287664D02*
X297997Y-285622D01*
X299307Y-284455D01*
X301054Y-283872D01*
X302582Y-284455D01*
X303674Y-285622D01*
X304547Y-287372D01*
X304765Y-289413D01*
X304547Y-291164D01*
X303674Y-292914D01*
X302363Y-294372D01*
X300835Y-294955D01*
X299089Y-294372D01*
X297560Y-292622D01*
X296687Y-289997D01*
X296469Y-287080D01*
X296905Y-283289D01*
X297560Y-281246D01*
X298652Y-279205D01*
X300180Y-277747D01*
X301709Y-277455D01*
X303237Y-278038D01*
X304329Y-279497D01*
G01X313969Y-287664D02*
X315497Y-285622D01*
X316807Y-284455D01*
X318554Y-283872D01*
X320082Y-284455D01*
X321174Y-285622D01*
X322047Y-287372D01*
X322265Y-289413D01*
X322047Y-291164D01*
X321174Y-292914D01*
X319863Y-294372D01*
X318335Y-294955D01*
X316589Y-294372D01*
X315060Y-292622D01*
X314187Y-289997D01*
X313969Y-287080D01*
X314405Y-283289D01*
X315060Y-281246D01*
X316152Y-279205D01*
X317680Y-277747D01*
X319209Y-277455D01*
X320737Y-278038D01*
X321829Y-279497D01*
G01X331905Y-292914D02*
X333434Y-294372D01*
X335180Y-294955D01*
X336927Y-294372D01*
X338455Y-292622D01*
X339547Y-289997D01*
X339984Y-287372D01*
Y-284164D01*
X339547Y-281539D01*
X338455Y-279205D01*
X337145Y-278038D01*
X335617Y-277455D01*
X333870Y-278038D01*
X332560Y-279205D01*
X331687Y-280955D01*
X331250Y-283289D01*
X331687Y-285330D01*
X332779Y-287372D01*
X334089Y-288539D01*
X335617Y-288830D01*
X337363Y-288247D01*
X338674Y-286788D01*
X339984Y-284164D01*
G01X395208Y-232455D02*
X400667Y-249955D01*
X406126Y-232455D01*
G01X422534Y-249955D02*
X413800D01*
Y-232455D01*
X422534D01*
G01X419040Y-240913D02*
X413800D01*
G01X431300Y-249955D02*
Y-232455D01*
X436759D01*
X438505Y-233330D01*
X439597Y-234497D01*
X440034Y-236830D01*
X439597Y-239164D01*
X438287Y-240622D01*
X436759Y-241497D01*
X431300D01*
G01X436759D02*
X440034Y-249955D01*
G01X453167Y-250538D02*
X452730Y-250247D01*
Y-249663D01*
X453167Y-249372D01*
X453604Y-249663D01*
Y-250247D01*
X453167Y-250538D01*
G01X426917Y-294955D02*
Y-277455D01*
X424297Y-280955D01*
G01Y-294955D02*
X429537D01*
G01X528750Y-232455D02*
Y-249955D01*
X537484D01*
G01X554547D02*
Y-238289D01*
G01Y-240330D02*
X553674Y-239164D01*
X552363Y-238580D01*
X550835Y-238289D01*
X549307Y-238872D01*
X547997Y-240038D01*
X547123Y-241788D01*
X546687Y-244122D01*
X547123Y-246455D01*
X547997Y-248205D01*
X549307Y-249372D01*
X550835Y-249955D01*
X552363Y-249663D01*
X553674Y-248789D01*
X554547Y-247622D01*
G01X563532Y-255205D02*
X564842Y-255788D01*
X566589Y-255205D01*
X567680Y-254039D01*
X568554Y-252580D01*
X569863Y-247914D01*
X572702Y-238289D01*
G01X565715D02*
X569863Y-247914D01*
G01X582342Y-242080D02*
X589329D01*
X588674Y-240038D01*
X587582Y-238872D01*
X586054Y-238289D01*
X584525Y-238580D01*
X583215Y-239455D01*
X582342Y-241497D01*
X581905Y-243247D01*
Y-244997D01*
X582342Y-246747D01*
X583434Y-248497D01*
X584744Y-249663D01*
X586272Y-249955D01*
X587800Y-249372D01*
X589329Y-247622D01*
G01X600060Y-249955D02*
Y-238289D01*
G01Y-240622D02*
X601152Y-239455D01*
X602244Y-238580D01*
X603772Y-238289D01*
X604863Y-238580D01*
X606174Y-239455D01*
G01X592621Y-285622D02*
X591747Y-284747D01*
X591092Y-283289D01*
X590655Y-281246D01*
X591092Y-279497D01*
X591965Y-278330D01*
X593494Y-277455D01*
X599389D01*
Y-294955D01*
X592184D01*
X590655Y-293789D01*
X589782Y-292038D01*
X589345Y-289997D01*
X589782Y-287955D01*
X591092Y-286205D01*
X592621Y-285622D01*
X599389D01*
G01X581452Y-292622D02*
X579705Y-294080D01*
X577740Y-294955D01*
X575994D01*
X574247Y-294080D01*
X572937Y-292622D01*
X572282Y-290580D01*
X572719Y-288539D01*
X573810Y-286788D01*
X575775Y-285622D01*
X578395Y-285038D01*
X579924Y-283872D01*
X580579Y-281830D01*
X580142Y-279788D01*
X579050Y-278330D01*
X577522Y-277455D01*
X575994D01*
X574465Y-278038D01*
X573155Y-279497D01*
G01X565044Y-294955D02*
Y-277455D01*
X559367Y-292038D01*
X553690Y-277455D01*
Y-294955D01*
G01X546670D02*
Y-277455D01*
X542304D01*
X540557Y-278330D01*
X539247Y-279497D01*
X538155Y-281246D01*
X537282Y-283289D01*
X537064Y-286205D01*
X537282Y-289122D01*
X538155Y-291164D01*
X539247Y-292914D01*
X540557Y-294080D01*
X542304Y-294955D01*
X546670D01*
G01X670864Y-249955D02*
Y-232455D01*
X675230D01*
X676977Y-233330D01*
X678287Y-234497D01*
X679379Y-236246D01*
X680252Y-238289D01*
X680470Y-241205D01*
X680252Y-244122D01*
X679379Y-246164D01*
X678287Y-247914D01*
X676977Y-249080D01*
X675230Y-249955D01*
X670864D01*
G01X689892Y-242080D02*
X696879D01*
X696224Y-240038D01*
X695132Y-238872D01*
X693604Y-238289D01*
X692075Y-238580D01*
X690765Y-239455D01*
X689892Y-241497D01*
X689455Y-243247D01*
Y-244997D01*
X689892Y-246747D01*
X690984Y-248497D01*
X692294Y-249663D01*
X693822Y-249955D01*
X695350Y-249372D01*
X696879Y-247622D01*
G01X707392Y-247914D02*
X708484Y-249080D01*
X710012Y-249955D01*
X711322D01*
X712632Y-249372D01*
X713505Y-248497D01*
X713942Y-247331D01*
X713724Y-245580D01*
X712850Y-244705D01*
X708920Y-242955D01*
X708047Y-240913D01*
X708484Y-239455D01*
X709357Y-238580D01*
X710667Y-238289D01*
X711977Y-238580D01*
X713287Y-239455D01*
G01X728167Y-238289D02*
Y-249955D01*
G01Y-233622D02*
X727730Y-233330D01*
Y-232747D01*
X728167Y-232455D01*
X728604Y-232747D01*
Y-233330D01*
X728167Y-233622D01*
G01X742610Y-254330D02*
X744139Y-255497D01*
X745885Y-255788D01*
X747413Y-255497D01*
X748724Y-254039D01*
X749597Y-251997D01*
Y-238289D01*
G01Y-240622D02*
X748724Y-239455D01*
X747413Y-238580D01*
X745885Y-238289D01*
X744139Y-238872D01*
X743047Y-240038D01*
X742173Y-242080D01*
X741737Y-244122D01*
X741955Y-245872D01*
X742829Y-247914D01*
X744139Y-249372D01*
X745885Y-249955D01*
X747195Y-249663D01*
X748724Y-248497D01*
X749597Y-247331D01*
G01X759455Y-249955D02*
Y-238289D01*
G01Y-241205D02*
X760329Y-239747D01*
X761639Y-238580D01*
X763385Y-238289D01*
X764913Y-238580D01*
X766224Y-239747D01*
X766879Y-241788D01*
Y-249955D01*
G01X777392Y-242080D02*
X784379D01*
X783724Y-240038D01*
X782632Y-238872D01*
X781104Y-238289D01*
X779575Y-238580D01*
X778265Y-239455D01*
X777392Y-241497D01*
X776955Y-243247D01*
Y-244997D01*
X777392Y-246747D01*
X778484Y-248497D01*
X779794Y-249663D01*
X781322Y-249955D01*
X782850Y-249372D01*
X784379Y-247622D01*
G01X795110Y-249955D02*
Y-238289D01*
G01Y-240622D02*
X796202Y-239455D01*
X797294Y-238580D01*
X798822Y-238289D01*
X799913Y-238580D01*
X801224Y-239455D01*
G01X660367Y-277455D02*
X663423Y-294955D01*
X666917Y-277455D01*
X670410Y-294955D01*
X673467Y-277455D01*
G01X680050Y-294955D02*
Y-277455D01*
X685290D01*
X687037Y-278330D01*
X688347Y-280372D01*
X688784Y-282705D01*
X688347Y-285038D01*
X687255Y-286788D01*
X685290Y-287664D01*
X680050D01*
G01X697332Y-294955D02*
Y-277455D01*
G01X706502D02*
Y-294955D01*
G01Y-286205D02*
X697332D01*
G01X716579Y-289122D02*
X722255D01*
G01X732769Y-294955D02*
Y-277455D01*
X741065D01*
G01X738009Y-285913D02*
X732769D01*
G01X750050Y-277455D02*
Y-294955D01*
X758784D01*
G01X771917D02*
X770170Y-294663D01*
X768642Y-293497D01*
X767332Y-291747D01*
X766458Y-289705D01*
X766022Y-287372D01*
Y-285038D01*
X766458Y-282705D01*
X767332Y-280663D01*
X768642Y-278914D01*
X770170Y-277747D01*
X771917Y-277455D01*
X773663Y-277747D01*
X775192Y-278914D01*
X776502Y-280663D01*
X777376Y-282705D01*
X777812Y-285038D01*
Y-287372D01*
X777376Y-289705D01*
X776502Y-291747D01*
X775192Y-293497D01*
X773663Y-294663D01*
X771917Y-294955D01*
G01X785050D02*
Y-277455D01*
X790509D01*
X792255Y-278330D01*
X793347Y-279497D01*
X793784Y-281830D01*
X793347Y-284164D01*
X792037Y-285622D01*
X790509Y-286497D01*
X785050D01*
G01X790509D02*
X793784Y-294955D01*
G01X801458D02*
X806917Y-277455D01*
X812376Y-294955D01*
G01X810410Y-288830D02*
X803423D01*
G01X841867Y-294955D02*
Y-277455D01*
X839247Y-280955D01*
G01Y-294955D02*
X844487D01*
G01X859367D02*
Y-277455D01*
X856747Y-280955D01*
G01Y-294955D02*
X861987D01*
G01X872937Y-295538D02*
X880797Y-277455D01*
G01X894367Y-294955D02*
Y-277455D01*
X891747Y-280955D01*
G01Y-294955D02*
X896987D01*
G01X907719Y-287664D02*
X909247Y-285622D01*
X910557Y-284455D01*
X912304Y-283872D01*
X913832Y-284455D01*
X914924Y-285622D01*
X915797Y-287372D01*
X916015Y-289413D01*
X915797Y-291164D01*
X914924Y-292914D01*
X913613Y-294372D01*
X912085Y-294955D01*
X910339Y-294372D01*
X908810Y-292622D01*
X907937Y-289997D01*
X907719Y-287080D01*
X908155Y-283289D01*
X908810Y-281246D01*
X909902Y-279205D01*
X911430Y-277747D01*
X912959Y-277455D01*
X914487Y-278038D01*
X915579Y-279497D01*
G01X925437Y-295538D02*
X933297Y-277455D01*
G01X942719Y-280372D02*
X944029Y-278622D01*
X945557Y-277747D01*
X947304Y-277455D01*
X949487Y-278038D01*
X951015Y-279497D01*
X951452Y-281246D01*
X951234Y-282997D01*
X950360Y-284455D01*
X945994Y-287372D01*
X944029Y-289413D01*
X942719Y-292331D01*
X942282Y-294955D01*
X951452D01*
G01X964367Y-277455D02*
X962620Y-278038D01*
X961310Y-279497D01*
X960437Y-281246D01*
X959782Y-283580D01*
X959564Y-286205D01*
X959782Y-288830D01*
X960437Y-291164D01*
X961310Y-292914D01*
X962620Y-294372D01*
X964367Y-294955D01*
X966113Y-294372D01*
X967424Y-292914D01*
X968297Y-291164D01*
X968952Y-288830D01*
X969170Y-286205D01*
X968952Y-283580D01*
X968297Y-281246D01*
X967424Y-279497D01*
X966113Y-278038D01*
X964367Y-277455D01*
G01X981867Y-294955D02*
Y-277455D01*
X979247Y-280955D01*
G01Y-294955D02*
X984487D01*
G01X995219Y-287664D02*
X996747Y-285622D01*
X998057Y-284455D01*
X999804Y-283872D01*
X1001332Y-284455D01*
X1002424Y-285622D01*
X1003297Y-287372D01*
X1003515Y-289413D01*
X1003297Y-291164D01*
X1002424Y-292914D01*
X1001113Y-294372D01*
X999585Y-294955D01*
X997839Y-294372D01*
X996310Y-292622D01*
X995437Y-289997D01*
X995219Y-287080D01*
X995655Y-283289D01*
X996310Y-281246D01*
X997402Y-279205D01*
X998930Y-277747D01*
X1000459Y-277455D01*
X1001987Y-278038D01*
X1003079Y-279497D01*
G01X889564Y-249955D02*
Y-232455D01*
X893930D01*
X895677Y-233330D01*
X896987Y-234497D01*
X898079Y-236246D01*
X898952Y-238289D01*
X899170Y-241205D01*
X898952Y-244122D01*
X898079Y-246164D01*
X896987Y-247914D01*
X895677Y-249080D01*
X893930Y-249955D01*
X889564D01*
G01X915797D02*
Y-238289D01*
G01Y-240330D02*
X914924Y-239164D01*
X913613Y-238580D01*
X912085Y-238289D01*
X910557Y-238872D01*
X909247Y-240038D01*
X908373Y-241788D01*
X907937Y-244122D01*
X908373Y-246455D01*
X909247Y-248205D01*
X910557Y-249372D01*
X912085Y-249955D01*
X913613Y-249663D01*
X914924Y-248789D01*
X915797Y-247622D01*
G01X929367Y-232455D02*
Y-249955D01*
G01X926310Y-238289D02*
X932424D01*
G01X943592Y-242080D02*
X950579D01*
X949924Y-240038D01*
X948832Y-238872D01*
X947304Y-238289D01*
X945775Y-238580D01*
X944465Y-239455D01*
X943592Y-241497D01*
X943155Y-243247D01*
Y-244997D01*
X943592Y-246747D01*
X944684Y-248497D01*
X945994Y-249663D01*
X947522Y-249955D01*
X949050Y-249372D01*
X950579Y-247622D01*
G01X-7874Y0D02*
X-75552D01*
G02X-90552Y15000I0J15000D01*
G01Y519024D01*
G02X-75552Y534024I15000J0D01*
G01X-7874D01*
G01Y1030087D02*
X-75552D01*
G03X-90552Y1015087I0J-15000D01*
G01Y1001780D01*
G03X-75552Y986780I15000J0D01*
G01X-7874D01*
G01Y1992126D02*
X-75552D01*
G03X-90552Y1977126I0J-15000D01*
G01Y1915165D01*
G03X-75552Y1900165I15000J0D01*
G01X-7874D01*
G01X1023228Y1618051D02*
Y1675945D01*
G02X1028701Y1681417I5472J0D01*
G01X1033465D01*
X1037402Y1685354D01*
Y1988189D01*
G03X1033465Y1992126I-3937J0D01*
G01X3937D01*
G03X0Y1988189I0J-3937D01*
G01Y1661189D01*
X1969Y1659220D01*
X17323D01*
G02Y1650559I0J-4331D01*
G01X1969D01*
X0Y1648591D01*
Y1243866D01*
X1969Y1241898D01*
X17323D01*
G02Y1233236I0J-4331D01*
G01X1969D01*
X0Y1231268D01*
Y747803D01*
X1969Y745835D01*
X17323D01*
G02Y737173I0J-4331D01*
G01X1969D01*
X0Y735205D01*
Y3937D01*
G03X3937Y0I3937J0D01*
G01X121260D01*
X127310Y11888D01*
G03X127953Y14567I-5263J2680D01*
G01Y17717D01*
G02X139764I5906J0D01*
G01Y14567D01*
G03X140406Y11888I5906J-1D01*
G01X146457Y0D01*
X1033465D01*
G03X1037402Y3937I0J3937D01*
G01Y1424882D01*
X1033465Y1428819D01*
X1028701D01*
G02X1023228Y1434291I0J5473D01*
G01Y1609902D01*
X1021260Y1611870D01*
X993681D01*
G02Y1616083I0J2107D01*
G01X1021260D01*
X1023228Y1618051D01*
G01X-7874Y39059D02*
G03X0I3937J0D01*
G01Y8350D02*
G03X-7874I-3937J0D01*
G01D02*
Y0D01*
G01Y251657D02*
Y39059D01*
G01X0Y251657D02*
G03X-7874I-3937J0D01*
G01Y282366D02*
G03X0I3937J0D01*
G01X-7874Y494965D02*
Y282366D01*
G01Y525673D02*
G03X0I3937J0D01*
G01Y494965D02*
G03X-7874I-3937J0D01*
G01Y534024D02*
Y525673D01*
G01X0Y993079D02*
G03X-7874I-3937J0D01*
G01Y986780D02*
Y993079D01*
G01Y1023787D02*
G03X0I3937J0D01*
G01X-7874D02*
Y1030087D01*
G01Y1930791D02*
Y1900165D01*
G01X0Y1930791D02*
G03X-7874I-3937J0D01*
G01Y1961500D02*
G03X0I3937J0D01*
G01X-7874Y1992126D02*
Y1961500D01*
G01X1045276Y0D02*
X1112953D01*
G03X1127953Y15000I0J15000D01*
G01Y493259D01*
G01X1045276Y25827D02*
G03X1037402I-3937J0D01*
G01X1045276Y0D02*
Y25827D01*
G01X1037402Y56535D02*
G03X1045276I3937J0D01*
G01D02*
Y284882D01*
G01X1037402Y315591D02*
G03X1045276I3937J0D01*
G01Y284882D02*
G03X1037402I-3937J0D01*
G01X1045276Y315591D02*
Y543937D01*
G01D02*
G03X1037402I-3937J0D01*
G01Y574646D02*
G03X1045276I3937J0D01*
G01D02*
Y802992D01*
G01X1037402Y833701D02*
G03X1045276I3937J0D01*
G01Y802992D02*
G03X1037402I-3937J0D01*
G01X1045276Y833701D02*
Y1062047D01*
G01D02*
G03X1037402I-3937J0D01*
G01Y1092756D02*
G03X1045276I3937J0D01*
G01D02*
Y1321102D01*
G01D02*
G03X1037402I-3937J0D01*
G01Y1351811D02*
G03X1045276I3937J0D01*
G01D02*
Y1377638D01*
G01D02*
X1112953D01*
G02X1127953Y1362638I0J-15000D01*
G01Y501133D01*
G01X1045276Y1732598D02*
X1112953D01*
G03X1127953Y1747598I0J15000D01*
G01Y1977126D01*
G03X1112953Y1992126I-15000J0D01*
G01X1045276D01*
G01X1037402Y1767835D02*
G03X1045276I3937J0D01*
G01Y1737126D02*
G03X1037402I-3937J0D01*
G01X1045276Y1767835D02*
Y1956890D01*
G01Y1732598D02*
Y1737126D01*
G01X1037402Y1987598D02*
G03X1045276I3937J0D01*
G01Y1956890D02*
G03X1037402I-3937J0D01*
G01X1045276Y1987598D02*
Y1992126D01*
G01X1127953Y501133D02*
G03Y493259I0J-3937D01*
M02*
